# BASEBOARD_FAB2 (Tioga Pass) — schematic netlist excerpt (pin names and nets, part order shuffled) for the footprints in the layout excerpt that follows; sources: Cadence DE-HDL packaged netlist, KiCad conversion of Wiwynn_Tioga_Pass_MB.brd

J4E1  SCONN120_H61426002  CONN  pkg SM  page 193
  IOA1  = PVCCMCP_CPU1
  IOA2  = PVCCMCP_CPU1
  IOA3  = PVCCMCP_CPU1
  IOA4  = VSENSE_PVCCMCP_CPU1_SKT_VSEN
  IOA5  = PVCCMCP_CPU1
  IOA6  = PVCCMCP_CPU1
  IOA7  = PVCCMCP_CPU1
  IOA8  = PVCCMCP_CPU1
  IOA9  = PVCCMCP_CPU1
  IOA10  = PVCCMCP_CPU1
  IOA11  = PVCCMCP_CPU1
  IOA12  = PVCCMCP_CPU1
  IOA13  = PVCCMCP_CPU1
  IOA14  = PVCCMCP_CPU1
  IOA15  = PVCCMCP_CPU1
  IOA16  = PVCCMCP_CPU1
  IOA17  = PVCCMCP_CPU1
  IOA18  = PVCCMCP_CPU1
  IOA19  = GND
  IOA20  = GND
  IOB1  = PVCCMCP_CPU1
  IOB2  = PVCCMCP_CPU1
  IOB3  = PVCCMCP_CPU1
  IOB4  = VSENSE_PVCCMCP_CPU1_SKT_VRTN
  IOB5  = PVCCMCP_CPU1
  IOB6  = PVCCMCP_CPU1
  IOB7  = PVCCMCP_CPU1
  IOB8  = PVCCMCP_CPU1
  IOB9  = PVCCMCP_CPU1
  IOB10  = PVCCMCP_CPU1
  IOB11  = PVCCMCP_CPU1
  IOB12  = PVCCMCP_CPU1
  IOB13  = PVCCMCP_CPU1
  IOB14  = PVCCMCP_CPU1
  IOB15  = PVCCMCP_CPU1
  IOB16  = PVCCMCP_CPU1
  IOB17  = PVCCMCP_CPU1
  IOB18  = PVCCMCP_CPU1
  IOB19  = GND
  IOB20  = GND
  IOC1  = PVCCMCP_CPU1
  IOC2  = PVCCMCP_CPU1
  IOC3  = PVCCMCP_CPU1
  IOC4  = PVCCMCP_CPU1
  IOC5  = PVCCMCP_CPU1
  IOC6  = PVCCMCP_CPU1
  IOC7  = PVCCMCP_CPU1
  IOC8  = PVCCMCP_CPU1
  IOC9  = PVCCMCP_CPU1
  IOC10  = PVCCMCP_CPU1
  IOC11  = PVCCMCP_CPU1
  IOC12  = PVCCMCP_CPU1
  IOC13  = PVCCMCP_CPU1
  IOC14  = PVCCMCP_CPU1
  IOC15  = PVCCMCP_CPU1
  IOC16  = PVCCMCP_CPU1
  IOC17  = PVCCMCP_CPU1
  IOC18  = PVCCMCP_CPU1
  IOC19  = GND
  IOC20  = GND
  IOD1  = VSENSE_P1V8MCP_CPU1_SKT_VSEN
  IOD2  = VSENSE_P1V8MCP_CPU1_SKT_VRTN
  IOD3  = P1V8_MCP_CPU1
  IOD4  = GND
  IOD5  = GND
  IOD6  = GND
  IOD7  = GND
  IOD8  = GND
  IOD9  = GND
  IOD10  = GND
  IOD11  = GND
  IOD12  = GND
  IOD13  = GND
  IOD14  = GND
  IOD15  = GND
  IOD16  = GND
  IOD17  = GND
  IOD18  = GND
  IOD19  = GND
  IOD20  = GND
  IOE1  = P1V8_MCP_CPU1
  IOE2  = P1V8_MCP_CPU1
  IOE3  = P1V8_MCP_CPU1
  IOE4  = GND
  IOE5  = CLK_322M_156M_CPU1_OSC_VRM_DP
  IOE6  = GND
  IOE7  = GND
  IOE8  = GND
  IOE9  = GND
  IOE10  = GND
  IOE11  = GND
  IOE12  = GND
  IOE13  = GND
  IOE14  = GND
  IOE15  = GND
  IOE16  = GND
  IOE17  = GND
  IOE18  = GND
  IOE19  = GND
  IOE20  = GND
  IOF1  = P1V8_MCP_CPU1
  IOF2  = P1V8_MCP_CPU1
  IOF3  = P1V8_MCP_CPU1
  IOF4  = GND
  IOF5  = CLK_322M_156M_CPU1_OSC_VRM_DN
  IOF6  = GND
  IOF7  = GND
  IOF8  = GND
  IOF9  = GND
  IOF10  = GND
  IOF11  = GND
  IOF12  = GND
  IOF13  = GND
  IOF14  = GND
  IOF15  = GND
  IOF16  = GND
  IOF17  = GND
  IOF18  = GND
  IOF19  = GND
  IOF20  = GND

(kicad_pcb
	(version 20260206)
	(generator "pcbnew")
	(generator_version "10.0")
	(general
		(thickness 1.6)
		(legacy_teardrops no)
	)
	(paper "A4")
	(title_block
		(title "Wiwynn_Tioga_Pass_MB.brd")
		(comment 1 "Tioga Pass / footprint 1695 of 4770 (J4E1), pads 50-101 of 122")
	)
	(layers
		(0 "F.Cu" signal "TOP")
		(4 "In1.Cu" signal "L2GND")
		(6 "In2.Cu" signal "L3")
		(8 "In3.Cu" signal "L4GND")
		(10 "In4.Cu" signal "L5")
		(12 "In5.Cu" signal "L6GND")
		(14 "In6.Cu" signal "L7VCC")
		(16 "In7.Cu" signal "L8VCC")
		(18 "In8.Cu" signal "L9GND")
		(20 "In9.Cu" signal "L10")
		(22 "In10.Cu" signal "L11GND")
		(24 "In11.Cu" signal "L12")
		(26 "In12.Cu" signal "L13GND")
		(2 "B.Cu" signal "BOTTOM")
		(9 "F.Adhes" user "F.Adhesive")
		(11 "B.Adhes" user "B.Adhesive")
		(13 "F.Paste" user "Package Geometry/Pastemask Top")
		(15 "B.Paste" user "Package Geometry/Pastemask Bottom")
		(5 "F.SilkS" user "Ref Des/Silkscreen Top")
		(7 "B.SilkS" user "Ref Des/Silkscreen Bottom")
		(1 "F.Mask" user "Board Geometry/Soldermask Top")
		(3 "B.Mask" user "Board Geometry/Soldermask Bottom")
		(17 "Dwgs.User" user "User.Drawings")
		(19 "Cmts.User" user "User.Comments")
		(21 "Eco1.User" user "User.Eco1")
		(23 "Eco2.User" user "User.Eco2")
		(25 "Edge.Cuts" user "Board Geometry/Outline")
		(27 "Margin" user)
		(31 "F.CrtYd" user "Package Geometry/Place Bound Top")
		(29 "B.CrtYd" user "Package Geometry/Place Bound Bottom")
		(35 "F.Fab" user "Ref Des/Assembly Top")
		(33 "B.Fab" user "Ref Des/Assembly Bottom")
	)
	(footprint ""
		(layer "F.Cu")
		(at 164.615114 -43.80103 90)
		(property "Reference" "J4E1"
			(at -3.59283 -5.018024 90)
			(unlocked yes)
			(layer "F.SilkS")
			(effects
				(font
					(size 0.7874 0.5842)
					(thickness 0.1524)
				)
			)
		)
		(property "Value" ""
			(at 0 0 90)
			(layer "F.Fab")
			(effects
				(font
					(size 1.27 1.27)
				)
			)
		)
		(duplicate_pad_numbers_are_jumpers no)
		(pad "C8" smd circle
			(at -2.54 8.89 90)
			(size 0.635 0.635)
			(layers "F.Cu" "F.Mask" "F.Paste")
			(net "PVCCMCP_CPU1")
		)
		(pad "C9" smd circle
			(at -2.54 10.16 90)
			(size 0.635 0.635)
			(layers "F.Cu" "F.Mask" "F.Paste")
			(net "PVCCMCP_CPU1")
		)
		(pad "C10" smd circle
			(at -2.54 11.43 90)
			(size 0.635 0.635)
			(layers "F.Cu" "F.Mask" "F.Paste")
			(net "PVCCMCP_CPU1")
		)
		(pad "C11" smd circle
			(at -2.54 12.7 90)
			(size 0.635 0.635)
			(layers "F.Cu" "F.Mask" "F.Paste")
			(net "PVCCMCP_CPU1")
		)
		(pad "C12" smd circle
			(at -2.54 13.97 90)
			(size 0.635 0.635)
			(layers "F.Cu" "F.Mask" "F.Paste")
			(net "PVCCMCP_CPU1")
		)
		(pad "C13" smd circle
			(at -2.54 15.24 90)
			(size 0.635 0.635)
			(layers "F.Cu" "F.Mask" "F.Paste")
			(net "PVCCMCP_CPU1")
		)
		(pad "C14" smd circle
			(at -2.54 16.51 90)
			(size 0.635 0.635)
			(layers "F.Cu" "F.Mask" "F.Paste")
			(net "PVCCMCP_CPU1")
		)
		(pad "C15" smd circle
			(at -2.54 17.78 90)
			(size 0.635 0.635)
			(layers "F.Cu" "F.Mask" "F.Paste")
			(net "PVCCMCP_CPU1")
		)
		(pad "C16" smd circle
			(at -2.54 19.05 90)
			(size 0.635 0.635)
			(layers "F.Cu" "F.Mask" "F.Paste")
			(net "PVCCMCP_CPU1")
		)
		(pad "C17" smd circle
			(at -2.54 20.32 90)
			(size 0.635 0.635)
			(layers "F.Cu" "F.Mask" "F.Paste")
			(net "PVCCMCP_CPU1")
		)
		(pad "C18" smd circle
			(at -2.54 21.59 90)
			(size 0.635 0.635)
			(layers "F.Cu" "F.Mask" "F.Paste")
			(net "PVCCMCP_CPU1")
		)
		(pad "C19" smd circle
			(at -2.54 22.86 90)
			(size 0.635 0.635)
			(layers "F.Cu" "F.Mask" "F.Paste")
			(net "GND")
		)
		(pad "C20" smd circle
			(at -2.54 24.13 90)
			(size 0.635 0.635)
			(layers "F.Cu" "F.Mask" "F.Paste")
			(net "GND")
		)
		(pad "D1" smd circle
			(at -3.81 0 90)
			(size 0.635 0.635)
			(layers "F.Cu" "F.Mask" "F.Paste")
			(net "VSENSE_P1V8MCP_CPU1_SKT_VSEN")
		)
		(pad "D2" smd circle
			(at -3.81 1.27 90)
			(size 0.635 0.635)
			(layers "F.Cu" "F.Mask" "F.Paste")
			(net "VSENSE_P1V8MCP_CPU1_SKT_VRTN")
		)
		(pad "D3" smd circle
			(at -3.81 2.54 90)
			(size 0.635 0.635)
			(layers "F.Cu" "F.Mask" "F.Paste")
			(net "P1V8_MCP_CPU1")
		)
		(pad "D4" smd circle
			(at -3.81 3.81 90)
			(size 0.635 0.635)
			(layers "F.Cu" "F.Mask" "F.Paste")
			(net "GND")
		)
		(pad "D5" smd circle
			(at -3.81 5.08 90)
			(size 0.635 0.635)
			(layers "F.Cu" "F.Mask" "F.Paste")
			(net "GND")
		)
		(pad "D6" smd circle
			(at -3.81 6.35 90)
			(size 0.635 0.635)
			(layers "F.Cu" "F.Mask" "F.Paste")
			(net "GND")
		)
		(pad "D7" smd circle
			(at -3.81 7.62 90)
			(size 0.635 0.635)
			(layers "F.Cu" "F.Mask" "F.Paste")
			(net "GND")
		)
		(pad "D8" smd circle
			(at -3.81 8.89 90)
			(size 0.635 0.635)
			(layers "F.Cu" "F.Mask" "F.Paste")
			(net "GND")
		)
		(pad "D9" smd circle
			(at -3.81 10.16 90)
			(size 0.635 0.635)
			(layers "F.Cu" "F.Mask" "F.Paste")
			(net "GND")
		)
		(pad "D10" smd circle
			(at -3.81 11.43 90)
			(size 0.635 0.635)
			(layers "F.Cu" "F.Mask" "F.Paste")
			(net "GND")
		)
		(pad "D11" smd circle
			(at -3.81 12.7 90)
			(size 0.635 0.635)
			(layers "F.Cu" "F.Mask" "F.Paste")
			(net "GND")
		)
		(pad "D12" smd circle
			(at -3.81 13.97 90)
			(size 0.635 0.635)
			(layers "F.Cu" "F.Mask" "F.Paste")
			(net "GND")
		)
		(pad "D13" smd circle
			(at -3.81 15.24 90)
			(size 0.635 0.635)
			(layers "F.Cu" "F.Mask" "F.Paste")
			(net "GND")
		)
		(pad "D14" smd circle
			(at -3.81 16.51 90)
			(size 0.635 0.635)
			(layers "F.Cu" "F.Mask" "F.Paste")
			(net "GND")
		)
		(pad "D15" smd circle
			(at -3.81 17.78 90)
			(size 0.635 0.635)
			(layers "F.Cu" "F.Mask" "F.Paste")
			(net "GND")
		)
		(pad "D16" smd circle
			(at -3.81 19.05 90)
			(size 0.635 0.635)
			(layers "F.Cu" "F.Mask" "F.Paste")
			(net "GND")
		)
		(pad "D17" smd circle
			(at -3.81 20.32 90)
			(size 0.635 0.635)
			(layers "F.Cu" "F.Mask" "F.Paste")
			(net "GND")
		)
		(pad "D18" smd circle
			(at -3.81 21.59 90)
			(size 0.635 0.635)
			(layers "F.Cu" "F.Mask" "F.Paste")
			(net "GND")
		)
		(pad "D19" smd circle
			(at -3.81 22.86 90)
			(size 0.635 0.635)
			(layers "F.Cu" "F.Mask" "F.Paste")
			(net "GND")
		)
		(pad "D20" smd circle
			(at -3.81 24.13 90)
			(size 0.635 0.635)
			(layers "F.Cu" "F.Mask" "F.Paste")
			(net "GND")
		)
		(pad "E1" smd circle
			(at -5.08 0 90)
			(size 0.635 0.635)
			(layers "F.Cu" "F.Mask" "F.Paste")
			(net "P1V8_MCP_CPU1")
		)
		(pad "E2" smd circle
			(at -5.08 1.27 90)
			(size 0.635 0.635)
			(layers "F.Cu" "F.Mask" "F.Paste")
			(net "P1V8_MCP_CPU1")
		)
		(pad "E3" smd circle
			(at -5.08 2.54 90)
			(size 0.635 0.635)
			(layers "F.Cu" "F.Mask" "F.Paste")
			(net "P1V8_MCP_CPU1")
		)
		(pad "E4" smd circle
			(at -5.08 3.81 90)
			(size 0.635 0.635)
			(layers "F.Cu" "F.Mask" "F.Paste")
			(net "GND")
		)
		(pad "E5" smd circle
			(at -5.08 5.08 90)
			(size 0.635 0.635)
			(layers "F.Cu" "F.Mask" "F.Paste")
			(net "CLK_322M_156M_CPU1_OSC_VRM_DP")
		)
		(pad "E6" smd circle
			(at -5.08 6.35 90)
			(size 0.635 0.635)
			(layers "F.Cu" "F.Mask" "F.Paste")
			(net "GND")
		)
		(pad "E7" smd circle
			(at -5.08 7.62 90)
			(size 0.635 0.635)
			(layers "F.Cu" "F.Mask" "F.Paste")
			(net "GND")
		)
		(pad "E8" smd circle
			(at -5.08 8.89 90)
			(size 0.635 0.635)
			(layers "F.Cu" "F.Mask" "F.Paste")
			(net "GND")
		)
		(pad "E9" smd circle
			(at -5.08 10.16 90)
			(size 0.635 0.635)
			(layers "F.Cu" "F.Mask" "F.Paste")
			(net "GND")
		)
		(pad "E10" smd circle
			(at -5.08 11.43 90)
			(size 0.635 0.635)
			(layers "F.Cu" "F.Mask" "F.Paste")
			(net "GND")
		)
		(pad "E11" smd circle
			(at -5.08 12.7 90)
			(size 0.635 0.635)
			(layers "F.Cu" "F.Mask" "F.Paste")
			(net "GND")
		)
		(pad "E12" smd circle
			(at -5.08 13.97 90)
			(size 0.635 0.635)
			(layers "F.Cu" "F.Mask" "F.Paste")
			(net "GND")
		)
		(pad "E13" smd circle
			(at -5.08 15.24 90)
			(size 0.635 0.635)
			(layers "F.Cu" "F.Mask" "F.Paste")
			(net "GND")
		)
		(pad "E14" smd circle
			(at -5.08 16.51 90)
			(size 0.635 0.635)
			(layers "F.Cu" "F.Mask" "F.Paste")
			(net "GND")
		)
		(pad "E15" smd circle
			(at -5.08 17.78 90)
			(size 0.635 0.635)
			(layers "F.Cu" "F.Mask" "F.Paste")
			(net "GND")
		)
		(pad "E16" smd circle
			(at -5.08 19.05 90)
			(size 0.635 0.635)
			(layers "F.Cu" "F.Mask" "F.Paste")
			(net "GND")
		)
		(pad "E17" smd circle
			(at -5.08 20.32 90)
			(size 0.635 0.635)
			(layers "F.Cu" "F.Mask" "F.Paste")
			(net "GND")
		)
		(pad "E18" smd circle
			(at -5.08 21.59 90)
			(size 0.635 0.635)
			(layers "F.Cu" "F.Mask" "F.Paste")
			(net "GND")
		)
		(pad "E19" smd circle
			(at -5.08 22.86 90)
			(size 0.635 0.635)
			(layers "F.Cu" "F.Mask" "F.Paste")
			(net "GND")
		)
	)
)
